# T6G (Grand Teton) — schematic netlist excerpt (pin names and nets, part order shuffled) for the footprints in the layout excerpt that follows; sources: Cadence DE-HDL packaged netlist, KiCad conversion of 04192023_DAF0TMB3IC0_F0TG_MB_C_brd_V02_OCP.brd

PU6  ISL99390FRZTR5935  ISL99390FRZ-TR5935 IC  pkg QFN21_6X5XB  page 194
  VOS  = PVDDCR_CPU0_P0_VOS1
  AGND  = GND
  VCC  = PVDDCR_CPU0_P0_VCC1
  PVCC  = PVDDCR_CPU0_P0_PVCC
  PGND1  = GND
  GL1  = NC_PVDDCR_CPU0_P0_GL1_1
  PGND2  = GND
  SW  = SW_PVDDCR_CPU0_P0_SW1
  VIN1  = SW_P12V_AUX_PVDDCR_CPU0_P0_FLT
  VIN2  = SW_P12V_AUX_PVDDCR_CPU0_P0_FLT
  DNC  = NC_PVDDCR_CPU0_P0_DNC1
  PHASE  = SW_PVDDCR_CPU0_P0_PH1
  BOOT  = SW_PVDDCR_CPU0_P0_BOOT1
  PWM  = PVDDCR_CPU0_P0_PWM1
  EN  = PVDDCR_CPU0_P0_VCC1
  TOUT_FLT  = PVDDCR_CPU0_P0_TEMP0
  LSET  = PVDDCR_CPU0_P0_LSET1
  IOUT  = PVDDCR_CPU0_P0_IMON1
  REFIN  = PVDDCR_CPU0_P0_VCCS
  PGND3  = GND
  GL2  = NC_PVDDCR_CPU0_P0_GL2_1

(kicad_pcb
	(version 20260206)
	(generator "pcbnew")
	(generator_version "10.0")
	(general
		(thickness 1.6)
		(legacy_teardrops no)
	)
	(paper "A4")
	(title_block
		(title "04192023_DAF0TMB3IC0_F0TG_MB_C_brd_V02_OCP.brd")
		(comment 1 "Grand Teton / footprints 1311-1311 of 8354")
	)
	(layers
		(0 "F.Cu" signal "TOP")
		(4 "In1.Cu" signal "GND")
		(6 "In2.Cu" signal "IN1")
		(8 "In3.Cu" signal "GND1")
		(10 "In4.Cu" signal "IN2")
		(12 "In5.Cu" signal "GND2")
		(14 "In6.Cu" signal "IN3")
		(16 "In7.Cu" signal "GND3")
		(18 "In8.Cu" signal "VCC")
		(20 "In9.Cu" signal "VCC1")
		(22 "In10.Cu" signal "GND4")
		(24 "In11.Cu" signal "IN4")
		(26 "In12.Cu" signal "GND5")
		(28 "In13.Cu" signal "IN5")
		(30 "In14.Cu" signal "GND6")
		(32 "In15.Cu" signal "IN6")
		(34 "In16.Cu" signal "GND7")
		(2 "B.Cu" signal "BOTTOM")
		(9 "F.Adhes" user "F.Adhesive")
		(11 "B.Adhes" user "B.Adhesive")
		(13 "F.Paste" user "Package Geometry/Pastemask Top")
		(15 "B.Paste" user "Package Geometry/Pastemask Bottom")
		(5 "F.SilkS" user "Ref Des/Silkscreen Top")
		(7 "B.SilkS" user "Ref Des/Silkscreen Bottom")
		(1 "F.Mask" user "Board Geometry/Soldermask Top")
		(3 "B.Mask" user "Board Geometry/Soldermask Bottom")
		(17 "Dwgs.User" user "User.Drawings")
		(19 "Cmts.User" user "User.Comments")
		(21 "Eco1.User" user "User.Eco1")
		(23 "Eco2.User" user "User.Eco2")
		(25 "Edge.Cuts" user "Board Geometry/Outline")
		(27 "Margin" user)
		(31 "F.CrtYd" user "Package Geometry/Place Bound Top")
		(29 "B.CrtYd" user "Package Geometry/Place Bound Bottom")
		(35 "F.Fab" user "Ref Des/Assembly Top")
		(33 "B.Fab" user "Ref Des/Assembly Bottom")
	)
	(footprint ""
		(layer "F.Cu")
		(at 364.313978 -177.771298 180)
		(property "Reference" "PU6"
			(at -0.973074 -6.571742 0)
			(unlocked yes)
			(layer "F.SilkS")
			(effects
				(font
					(size 0.7874 0.5842)
					(thickness 0.1524)
				)
				(justify left)
			)
		)
		(property "Value" ""
			(at 0 0 180)
			(layer "F.Fab")
			(effects
				(font
					(size 1.27 1.27)
				)
			)
		)
		(duplicate_pad_numbers_are_jumpers no)
		(fp_line
			(start 2.500122 2.999994)
			(end 2.2987 2.999994)
			(stroke
				(width 0.1524)
				(type default)
			)
			(layer "F.SilkS")
		)
		(fp_line
			(start 2.500122 2.339594)
			(end 2.500122 2.999994)
			(stroke
				(width 0.1524)
				(type default)
			)
			(layer "F.SilkS")
		)
		(fp_line
			(start 2.500122 -2.999994)
			(end 2.500122 -2.44348)
			(stroke
				(width 0.1524)
				(type default)
			)
			(layer "F.SilkS")
		)
		(fp_line
			(start 2.31394 -2.999994)
			(end 2.500122 -2.999994)
			(stroke
				(width 0.1524)
				(type default)
			)
			(layer "F.SilkS")
		)
		(fp_line
			(start -2.2987 2.999994)
			(end -2.500122 2.999994)
			(stroke
				(width 0.1524)
				(type default)
			)
			(layer "F.SilkS")
		)
		(fp_line
			(start -2.500122 2.999994)
			(end -2.500122 2.339594)
			(stroke
				(width 0.1524)
				(type default)
			)
			(layer "F.SilkS")
		)
		(fp_line
			(start -2.500122 0.6604)
			(end -2.500122 0.229108)
			(stroke
				(width 0.1524)
				(type default)
			)
			(layer "F.SilkS")
		)
		(fp_line
			(start -2.500122 -2.529078)
			(end -2.500122 -2.999994)
			(stroke
				(width 0.1524)
				(type default)
			)
			(layer "F.SilkS")
		)
		(fp_line
			(start -2.500122 -2.999994)
			(end -2.24409 -2.999994)
			(stroke
				(width 0.1524)
				(type default)
			)
			(layer "F.SilkS")
		)
		(fp_poly
			(pts
				(xy -2.686558 -2.45618) (xy -3.376422 -2.68605) (xy -2.916428 -3.146044)
			)
			(stroke
				(width 0)
				(type default)
			)
			(fill yes)
			(layer "F.SilkS")
		)
		(fp_line
			(start 2.500122 2.999994)
			(end -2.500122 2.999994)
			(stroke
				(width 0.1)
				(type default)
			)
			(layer "F.Fab")
		)
		(fp_line
			(start 2.500122 -2.999994)
			(end 2.500122 2.999994)
			(stroke
				(width 0.1)
				(type default)
			)
			(layer "F.Fab")
		)
		(fp_line
			(start -2.500122 2.999994)
			(end -2.500122 -2.999994)
			(stroke
				(width 0.1)
				(type default)
			)
			(layer "F.Fab")
		)
		(fp_line
			(start -2.500122 -2.999994)
			(end 2.500122 -2.999994)
			(stroke
				(width 0.1)
				(type default)
			)
			(layer "F.Fab")
		)
		(fp_poly
			(pts
				(xy -4.218432 -2.783078) (xy -4.218432 -1.767078) (xy -3.202432 -2.275078)
			)
			(stroke
				(width 0)
				(type default)
			)
			(fill yes)
			(layer "F.Fab")
		)
		(pad "1" smd rect
			(at -2.400046 -2.275078 270)
			(size 0.2286 0.6096)
			(layers "F.Cu" "F.Mask" "F.Paste")
			(net "PVDDCR_CPU0_P0_VOS1")
		)
		(pad "2" smd rect
			(at -2.400046 -1.82499 270)
			(size 0.2286 0.6096)
			(layers "F.Cu" "F.Mask" "F.Paste")
			(net "GND")
		)
		(pad "3" smd rect
			(at -2.400046 -1.374902 270)
			(size 0.2286 0.6096)
			(layers "F.Cu" "F.Mask" "F.Paste")
			(net "PVDDCR_CPU0_P0_VCC1")
		)
		(pad "4" smd rect
			(at -2.400046 -0.925068 270)
			(size 0.2286 0.6096)
			(layers "F.Cu" "F.Mask" "F.Paste")
			(net "PVDDCR_CPU0_P0_PVCC")
		)
		(pad "5" smd rect
			(at -2.400046 -0.47498 270)
			(size 0.2286 0.6096)
			(layers "F.Cu" "F.Mask" "F.Paste")
			(net "GND")
		)
		(pad "6" smd rect
			(at -2.400046 -0.024892 270)
			(size 0.2286 0.6096)
			(layers "F.Cu" "F.Mask" "F.Paste")
			(net "NC_PVDDCR_CPU0_P0_GL1_1")
		)
		(pad "7_9-20_24" smd circle
			(at 0 1.150112 270)
			(size 0 0)
			(layers "F.Cu" "F.Mask" "F.Paste")
			(net "GND")
		)
		(pad "10_19" smd rect
			(at 0 2.899918 270)
			(size 0.6096 4.318)
			(layers "F.Cu" "F.Mask" "F.Paste")
			(net "SW_PVDDCR_CPU0_P0_SW1")
		)
		(pad "25_29" smd rect
			(at 1.549908 -1.279906 90)
			(size 2.0574 2.3114)
			(layers "F.Cu" "F.Mask" "F.Paste")
			(net "SW_P12V_AUX_PVDDCR_CPU0_P0_FLT")
		)
		(pad "30" smd rect
			(at 2.05994 -2.899918 180)
			(size 0.2286 0.6096)
			(layers "F.Cu" "F.Mask" "F.Paste")
			(net "SW_P12V_AUX_PVDDCR_CPU0_P0_FLT")
		)
		(pad "31" smd rect
			(at 1.610106 -2.899918 180)
			(size 0.2286 0.6096)
			(layers "F.Cu" "F.Mask" "F.Paste")
			(net "NC_PVDDCR_CPU0_P0_DNC1")
		)
		(pad "32" smd rect
			(at 1.160018 -2.899918 180)
			(size 0.2286 0.6096)
			(layers "F.Cu" "F.Mask" "F.Paste")
			(net "SW_PVDDCR_CPU0_P0_PH1")
		)
		(pad "33" smd rect
			(at 0.70993 -2.899918 180)
			(size 0.2286 0.6096)
			(layers "F.Cu" "F.Mask" "F.Paste")
			(net "SW_PVDDCR_CPU0_P0_BOOT1")
		)
		(pad "34" smd rect
			(at 0.260096 -2.899918 180)
			(size 0.2286 0.6096)
			(layers "F.Cu" "F.Mask" "F.Paste")
			(net "PVDDCR_CPU0_P0_PWM1")
		)
		(pad "35" smd rect
			(at -0.189992 -2.899918 180)
			(size 0.2286 0.6096)
			(layers "F.Cu" "F.Mask" "F.Paste")
			(net "PVDDCR_CPU0_P0_VCC1")
		)
		(pad "36" smd rect
			(at -0.64008 -2.899918 180)
			(size 0.2286 0.6096)
			(layers "F.Cu" "F.Mask" "F.Paste")
			(net "PVDDCR_CPU0_P0_TEMP0")
		)
		(pad "37" smd rect
			(at -1.089914 -2.899918 180)
			(size 0.2286 0.6096)
			(layers "F.Cu" "F.Mask" "F.Paste")
			(net "PVDDCR_CPU0_P0_LSET1")
		)
		(pad "38" smd rect
			(at -1.540002 -2.899918 180)
			(size 0.2286 0.6096)
			(layers "F.Cu" "F.Mask" "F.Paste")
			(net "PVDDCR_CPU0_P0_IMON1")
		)
		(pad "39" smd rect
			(at -1.99009 -2.899918 180)
			(size 0.2286 0.6096)
			(layers "F.Cu" "F.Mask" "F.Paste")
			(net "PVDDCR_CPU0_P0_VCCS")
		)
		(pad "40" smd rect
			(at -0.87503 -1.27508 180)
			(size 1.7526 1.9558)
			(layers "F.Cu" "F.Mask" "F.Paste")
			(net "GND")
		)
		(pad "41" smd rect
			(at -1.525016 0.249936 90)
			(size 0.3048 0.4572)
			(layers "F.Cu" "F.Mask" "F.Paste")
			(net "NC_PVDDCR_CPU0_P0_GL2_1")
		)
		(zone
			(layer "F.Cu")
			(hatch none 0.5)
			(connect_pads
				(clearance 0)
			)
			(min_thickness 0.25)
			(keepout
				(tracks not_allowed)
				(vias allowed)
				(pads allowed)
				(copperpour not_allowed)
				(footprints allowed)
			)
			(placement
				(enabled no)
				(sheetname "")
			)
			(fill
				(thermal_gap 0.5)
				(thermal_bridge_width 0.5)
				(island_removal_mode 0)
			)
			(polygon
				(pts
					(xy 366.8141 -180.353462) (xy 366.8141 -180.021992) (xy 361.813856 -180.021992) (xy 361.813856 -180.350668)
					(xy 362.104178 -180.350668) (xy 362.104178 -180.315616) (xy 366.523778 -180.315616) (xy 366.523778 -180.353462)
				)
			)
		)
		(zone
			(layer "F.Cu")
			(hatch none 0.5)
			(connect_pads
				(clearance 0)
			)
			(min_thickness 0.25)
			(keepout
				(tracks not_allowed)
				(vias allowed)
				(pads allowed)
				(copperpour not_allowed)
				(footprints allowed)
			)
			(placement
				(enabled no)
				(sheetname "")
			)
			(fill
				(thermal_gap 0.5)
				(thermal_bridge_width 0.5)
				(island_removal_mode 0)
			)
			(polygon
				(pts
					(xy 364.261908 -177.52314) (xy 364.261908 -175.467518) (xy 366.116108 -175.467518) (xy 366.116108 -175.708564)
					(xy 366.358424 -175.708564) (xy 366.358424 -175.22698) (xy 362.445808 -175.22698) (xy 362.445808 -175.411892)
					(xy 363.97057 -175.411892) (xy 363.97057 -177.570892) (xy 361.813856 -177.570892) (xy 361.813856 -177.820574)
					(xy 363.964474 -177.820574)
				)
			)
		)
	)
)
